FILE_TYPE = CONNECTIVITY;
{Allegro Design Entry HDL 17.2-2016 S081 (4005846) 1/11/2022}
"PAGE_NUMBER" = 86;
0"NC";
1"M_B_CPU0_SA_CB<7:0>";
2"M_B_CPU0_SA_CA<6:0>";
3"M_B_CPU0_SB_CA<6:0>";
4"M_B_CPU0_SB_CB<7:0>";
5"M_B_CPU0_SA_DQ<31:0>";
6"M_B_CPU0_SB_DQ<31:0>";
7"M_B_CPU0_SB_DQS_DN<9:0>";
8"M_B_CPU0_SB_DQS_DP<9:0>";
9"M_B_CPU0_SA_DQS_DN<9:0>";
10"M_B_CPU0_SA_DQS_DP<9:0>";
11"GND\g";
12"GND\g";
13"P3V3_STBY\g";
14"I3C_SPD_DDRB_CPU0_SCL";
15"I3C_SPD_DDRAF_CPU0_SCL";
16"PWRGD_CHB_CPU0_DIMM";
17"I3C_SPD_DDRAF_CPU0_SDA";
18"P3V3_STBY\g";
19"M_B_CPU0_ALERT_N";
20"PD_CHB_CPU0_DIMM_SAA";
21"TP_CHB_CPU0_DIMM_RFU_6";
22"TP_CHB_CPU0_DIMM_RFU_5";
23"TP_CHB_CPU0_DIMM_RFU_4";
24"P12V_MEM_1\g";
25"GND\g";
26"GND\g";
27"GND\g";
28"TP_CHB_CPU0_DIMM_RFU_3";
29"TP_CHB_CPU0_DIMM_RFU_0";
30"TP_CHB_CPU0_DIMM_RFU_1";
31"TP_CHB_CPU0_DIMM_RFU_2";
32"M_B_CPU0_RESET_N";
33"M_B_CPU0_SB_CB<3>";
34"M_B_CPU0_SB_CB<0>";
35"M_B_CPU0_SB_CB<1>";
36"M_B_CPU0_SB_CB<2>";
37"M_B_CPU0_SB_DQ<24>";
38"M_B_CPU0_SB_DQ<30>";
39"M_B_CPU0_CLK_DP<0>";
40"M_B_CPU0_SB_CS_N<0>";
41"M_B_CPU0_SA_PAR";
42"M_B_CPU0_SB_PAR";
43"M_B_CPU0_SA_DQ<26>";
44"M_B_CPU0_SA_DQ<25>";
45"M_B_CPU0_SB_DQS_DP<9>";
46"M_B_CPU0_SB_DQS_DN<9>";
47"M_B_CPU0_SA_DQS_DN<0>";
48"M_B_CPU0_SA_DQS_DP<0>";
49"M_B_CPU0_SA_DQS_DP<9>";
50"M_B_CPU0_SA_DQS_DN<9>";
51"M_B_CPU0_SA_DQS_DP<8>";
52"M_B_CPU0_SA_DQS_DN<8>";
53"M_B_CPU0_SB_DQS_DN<7>";
54"M_B_CPU0_SA_DQS_DP<7>";
55"M_B_CPU0_SB_DQS_DP<6>";
56"M_B_CPU0_SB_DQS_DN<6>";
57"M_B_CPU0_SA_DQS_DN<6>";
58"M_B_CPU0_SB_DQS_DP<5>";
59"M_B_CPU0_SB_DQS_DN<5>";
60"M_B_CPU0_SA_DQS_DP<5>";
61"M_B_CPU0_SA_DQS_DN<5>";
62"M_B_CPU0_SB_DQS_DP<4>";
63"M_B_CPU0_SB_DQS_DN<4>";
64"M_B_CPU0_SA_DQS_DP<4>";
65"M_B_CPU0_SA_DQS_DN<4>";
66"M_B_CPU0_SB_DQS_DP<3>";
67"M_B_CPU0_SB_DQS_DN<3>";
68"M_B_CPU0_SA_DQS_DP<3>";
69"M_B_CPU0_SA_DQS_DN<3>";
70"M_B_CPU0_SB_DQS_DP<2>";
71"M_B_CPU0_SB_DQS_DN<2>";
72"M_B_CPU0_SA_DQS_DP<2>";
73"M_B_CPU0_SA_DQS_DN<2>";
74"M_B_CPU0_SB_DQS_DP<1>";
75"M_B_CPU0_SB_DQS_DN<1>";
76"M_B_CPU0_SA_DQS_DP<1>";
77"M_B_CPU0_SA_DQS_DN<1>";
78"M_B_CPU0_SB_DQS_DP<0>";
79"M_B_CPU0_SB_DQS_DN<0>";
80"M_B_CPU0_SB_DQS_DP<7>";
81"M_B_CPU0_SB_DQS_DN<8>";
82"M_B_CPU0_SB_DQS_DP<8>";
83"M_B_CPU0_SA_DQS_DP<6>";
84"M_B_CPU0_SA_DQS_DN<7>";
85"M_B_CPU0_SA_DQ<27>";
86"M_B_CPU0_SA_DQ<28>";
87"M_B_CPU0_SA_CA<6>";
88"M_B_CPU0_SA_DQ<19>";
89"M_B_CPU0_SA_DQ<18>";
90"M_B_CPU0_SB_RSP<0>";
91"M_B_CPU0_SA_RSP<0>";
92"M_B_CPU0_SB_DQ<0>";
93"M_B_CPU0_SB_DQ<1>";
94"M_B_CPU0_SB_DQ<2>";
95"M_B_CPU0_SB_DQ<3>";
96"M_B_CPU0_SB_DQ<4>";
97"M_B_CPU0_SB_DQ<5>";
98"M_B_CPU0_SB_DQ<6>";
99"M_B_CPU0_SB_DQ<7>";
100"M_B_CPU0_SB_DQ<8>";
101"M_B_CPU0_SB_DQ<9>";
102"M_B_CPU0_SB_DQ<10>";
103"M_B_CPU0_SB_DQ<11>";
104"M_B_CPU0_SB_DQ<12>";
105"M_B_CPU0_SB_DQ<13>";
106"M_B_CPU0_SB_DQ<14>";
107"M_B_CPU0_SB_DQ<15>";
108"M_B_CPU0_SB_DQ<16>";
109"M_B_CPU0_SB_DQ<17>";
110"M_B_CPU0_SB_DQ<18>";
111"M_B_CPU0_SB_DQ<19>";
112"M_B_CPU0_SB_DQ<20>";
113"M_B_CPU0_SB_DQ<21>";
114"M_B_CPU0_SB_DQ<22>";
115"M_B_CPU0_SB_DQ<23>";
116"M_B_CPU0_SB_DQ<25>";
117"M_B_CPU0_SB_DQ<26>";
118"M_B_CPU0_SB_DQ<27>";
119"M_B_CPU0_SB_DQ<28>";
120"M_B_CPU0_SB_DQ<29>";
121"M_B_CPU0_SB_DQ<31>";
122"M_B_CPU0_SA_DQ<0>";
123"M_B_CPU0_SA_DQ<1>";
124"M_B_CPU0_SA_DQ<2>";
125"M_B_CPU0_SA_DQ<3>";
126"M_B_CPU0_SA_DQ<4>";
127"M_B_CPU0_SA_DQ<5>";
128"M_B_CPU0_SA_DQ<6>";
129"M_B_CPU0_SA_DQ<7>";
130"M_B_CPU0_SA_DQ<8>";
131"M_B_CPU0_SA_DQ<9>";
132"M_B_CPU0_SA_DQ<10>";
133"M_B_CPU0_SA_DQ<11>";
134"M_B_CPU0_SA_DQ<12>";
135"M_B_CPU0_SA_DQ<13>";
136"M_B_CPU0_SA_DQ<14>";
137"M_B_CPU0_SA_DQ<15>";
138"M_B_CPU0_SA_DQ<16>";
139"M_B_CPU0_SA_DQ<17>";
140"M_B_CPU0_SA_DQ<20>";
141"M_B_CPU0_SA_DQ<21>";
142"M_B_CPU0_SA_DQ<22>";
143"M_B_CPU0_SA_DQ<23>";
144"M_B_CPU0_SA_DQ<24>";
145"M_B_CPU0_SA_DQ<29>";
146"M_B_CPU0_SA_DQ<30>";
147"M_B_CPU0_SB_CS_N<1>";
148"M_B_CPU0_SA_CS_N<1>";
149"M_B_CPU0_SA_CS_N<0>";
150"M_B_CPU0_CLK_DN<0>";
151"M_B_CPU0_SB_CB<4>";
152"M_B_CPU0_SB_CB<5>";
153"M_B_CPU0_SB_CB<6>";
154"M_B_CPU0_SA_CB<0>";
155"M_B_CPU0_SA_CB<2>";
156"M_B_CPU0_SA_CB<3>";
157"M_B_CPU0_SA_CB<5>";
158"M_B_CPU0_SA_CB<6>";
159"M_B_CPU0_SB_CA<6>";
160"M_B_CPU0_SB_CA<5>";
161"M_B_CPU0_SA_CA<5>";
162"M_B_CPU0_SB_CA<4>";
163"M_B_CPU0_SA_CA<4>";
164"M_B_CPU0_SB_CA<3>";
165"M_B_CPU0_SA_CA<3>";
166"M_B_CPU0_SB_CA<2>";
167"M_B_CPU0_SA_CA<2>";
168"M_B_CPU0_SB_CA<1>";
169"M_B_CPU0_SA_CA<1>";
170"M_B_CPU0_SB_CA<0>";
171"M_B_CPU0_SA_CA<0>";
172"M_B_CPU0_SB_CB<7>";
173"M_B_CPU0_SA_CB<1>";
174"M_B_CPU0_SA_CB<4>";
175"M_B_CPU0_SA_CB<7>";
176"M_B_CPU0_SA_DQ<31>";
177"PWRGD_CHAF_CPU0";
178"PD_CHB_CPU0_DIMM_SAA";
%"GND"
"1","(-2125,1825)","0","mstr_symbols","I150";
;
SIZE"1B"
CDS_LIB"mstr_symbols"
BODY_TYPE"PLUMBING"
VOLTAGE"0.0"
HDL_POWER"GND";
"A\NAC"27;
%"GND"
"1","(-325,1650)","0","mstr_symbols","I152";
;
SIZE"1B"
CDS_LIB"mstr_symbols"
BODY_TYPE"PLUMBING"
VOLTAGE"0.0"
HDL_POWER"GND";
"A\NAC"26;
%"VCC_CORE"
"1","(-8925,3575)","0","mstr_symbols","I177";
;
HDL_POWER"P3V3_STBY"
CDS_LIB"mstr_symbols"
VOLTAGE"3.3"
ROOM"PVCCINFAON_CPU0_CTRL";
"A"18;
%"TAP"
"1","(-7950,3375)","2","mstr_standard","I187";
;
CDS_LIB"mstr_standard"
BODY_TYPE"PLUMBING"
HDL_TAP"TRUE";
"B \NAC \NWC"4;
"S \NAC"
BN"1"35;
%"TAP"
"1","(-7950,3425)","2","mstr_standard","I188";
;
CDS_LIB"mstr_standard"
BODY_TYPE"PLUMBING"
HDL_TAP"TRUE";
"B \NAC \NWC"4;
"S \NAC"
BN"2"36;
%"TAP"
"1","(-7950,3325)","2","mstr_standard","I189";
;
CDS_LIB"mstr_standard"
BODY_TYPE"PLUMBING"
HDL_TAP"TRUE";
"B \NAC \NWC"4;
"S \NAC"
BN"0"34;
%"TAP"
"1","(-7950,3475)","2","mstr_standard","I190";
;
CDS_LIB"mstr_standard"
BODY_TYPE"PLUMBING"
HDL_TAP"TRUE";
"B \NAC \NWC"4;
"S \NAC"
BN"3"33;
%"TAP"
"1","(-7950,3525)","2","mstr_standard","I191";
;
CDS_LIB"mstr_standard"
BODY_TYPE"PLUMBING"
HDL_TAP"TRUE";
"B \NAC \NWC"4;
"S \NAC"
BN"4"151;
%"TAP"
"1","(-7950,3575)","2","mstr_standard","I192";
;
CDS_LIB"mstr_standard"
BODY_TYPE"PLUMBING"
HDL_TAP"TRUE";
"B \NAC \NWC"4;
"S \NAC"
BN"5"152;
%"TAP"
"1","(-7950,3675)","2","mstr_standard","I193";
;
CDS_LIB"mstr_standard"
BODY_TYPE"PLUMBING"
HDL_TAP"TRUE";
"B \NAC \NWC"4;
"S \NAC"
BN"7"172;
%"TAP"
"1","(-7950,3625)","2","mstr_standard","I194";
;
CDS_LIB"mstr_standard"
BODY_TYPE"PLUMBING"
HDL_TAP"TRUE";
"B \NAC \NWC"4;
"S \NAC"
BN"6"153;
%"TAP"
"1","(-7950,3875)","2","mstr_standard","I195";
;
CDS_LIB"mstr_standard"
BODY_TYPE"PLUMBING"
HDL_TAP"TRUE";
"B \NAC \NWC"1;
"S \NAC"
BN"2"155;
%"TAP"
"1","(-7950,3825)","2","mstr_standard","I196";
;
CDS_LIB"mstr_standard"
BODY_TYPE"PLUMBING"
HDL_TAP"TRUE";
"B \NAC \NWC"1;
"S \NAC"
BN"1"173;
%"TAP"
"1","(-7950,3775)","2","mstr_standard","I197";
;
CDS_LIB"mstr_standard"
BODY_TYPE"PLUMBING"
HDL_TAP"TRUE";
"B \NAC \NWC"1;
"S \NAC"
BN"0"154;
%"TAP"
"1","(-7950,3925)","2","mstr_standard","I198";
;
CDS_LIB"mstr_standard"
BODY_TYPE"PLUMBING"
HDL_TAP"TRUE";
"B \NAC \NWC"1;
"S \NAC"
BN"3"156;
%"TAP"
"1","(-7950,3975)","2","mstr_standard","I199";
;
CDS_LIB"mstr_standard"
BODY_TYPE"PLUMBING"
HDL_TAP"TRUE";
"B \NAC \NWC"1;
"S \NAC"
BN"4"174;
%"TAP"
"1","(-7950,4025)","2","mstr_standard","I200";
;
CDS_LIB"mstr_standard"
BODY_TYPE"PLUMBING"
HDL_TAP"TRUE";
"B \NAC \NWC"1;
"S \NAC"
BN"5"157;
%"TAP"
"1","(-7950,4075)","2","mstr_standard","I201";
;
CDS_LIB"mstr_standard"
BODY_TYPE"PLUMBING"
HDL_TAP"TRUE";
"B \NAC \NWC"1;
"S \NAC"
BN"6"158;
%"TAP"
"1","(-7950,4125)","2","mstr_standard","I202";
;
CDS_LIB"mstr_standard"
BODY_TYPE"PLUMBING"
HDL_TAP"TRUE";
"B \NAC \NWC"1;
"S \NAC"
BN"7"175;
%"TAP"
"1","(-7950,4975)","2","mstr_standard","I203";
;
CDS_LIB"mstr_standard"
BODY_TYPE"PLUMBING"
HDL_TAP"TRUE";
"B \NAC \NWC"3;
"S \NAC"
BN"3"164;
%"TAP"
"1","(-7950,4875)","2","mstr_standard","I204";
;
CDS_LIB"mstr_standard"
BODY_TYPE"PLUMBING"
HDL_TAP"TRUE";
"B \NAC \NWC"3;
"S \NAC"
BN"1"168;
%"TAP"
"1","(-7950,4825)","2","mstr_standard","I205";
;
CDS_LIB"mstr_standard"
BODY_TYPE"PLUMBING"
HDL_TAP"TRUE";
"B \NAC \NWC"3;
"S \NAC"
BN"0"170;
%"TAP"
"1","(-7950,4925)","2","mstr_standard","I206";
;
CDS_LIB"mstr_standard"
BODY_TYPE"PLUMBING"
HDL_TAP"TRUE";
"B \NAC \NWC"3;
"S \NAC"
BN"2"166;
%"TAP"
"1","(-6250,2375)","0","mstr_standard","I207";
;
CDS_LIB"mstr_standard"
BODY_TYPE"PLUMBING"
HDL_TAP"TRUE";
"B \NAC \NWC"6;
"S \NAC"
BN"1"93;
%"TAP"
"1","(-6250,2325)","0","mstr_standard","I208";
;
CDS_LIB"mstr_standard"
BODY_TYPE"PLUMBING"
HDL_TAP"TRUE";
"B \NAC \NWC"6;
"S \NAC"
BN"0"92;
%"TAP"
"1","(-6250,2425)","0","mstr_standard","I209";
;
CDS_LIB"mstr_standard"
BODY_TYPE"PLUMBING"
HDL_TAP"TRUE";
"B \NAC \NWC"6;
"S \NAC"
BN"2"94;
%"TAP"
"1","(-6250,2475)","0","mstr_standard","I210";
;
CDS_LIB"mstr_standard"
BODY_TYPE"PLUMBING"
HDL_TAP"TRUE";
"B \NAC \NWC"6;
"S \NAC"
BN"3"95;
%"TAP"
"1","(-6250,2525)","0","mstr_standard","I211";
;
CDS_LIB"mstr_standard"
BODY_TYPE"PLUMBING"
HDL_TAP"TRUE";
"B \NAC \NWC"6;
"S \NAC"
BN"4"96;
%"TAP"
"1","(-6250,2575)","0","mstr_standard","I212";
;
CDS_LIB"mstr_standard"
BODY_TYPE"PLUMBING"
HDL_TAP"TRUE";
"B \NAC \NWC"6;
"S \NAC"
BN"5"97;
%"TAP"
"1","(-6250,2675)","0","mstr_standard","I213";
;
CDS_LIB"mstr_standard"
BODY_TYPE"PLUMBING"
HDL_TAP"TRUE";
"B \NAC \NWC"6;
"S \NAC"
BN"7"99;
%"TAP"
"1","(-6250,2625)","0","mstr_standard","I214";
;
CDS_LIB"mstr_standard"
BODY_TYPE"PLUMBING"
HDL_TAP"TRUE";
"B \NAC \NWC"6;
"S \NAC"
BN"6"98;
%"TAP"
"1","(-6250,2725)","0","mstr_standard","I215";
;
CDS_LIB"mstr_standard"
BODY_TYPE"PLUMBING"
HDL_TAP"TRUE";
"B \NAC \NWC"6;
"S \NAC"
BN"8"100;
%"TAP"
"1","(-6250,2775)","0","mstr_standard","I216";
;
CDS_LIB"mstr_standard"
BODY_TYPE"PLUMBING"
HDL_TAP"TRUE";
"B \NAC \NWC"6;
"S \NAC"
BN"9"101;
%"TAP"
"1","(-6250,2825)","0","mstr_standard","I217";
;
CDS_LIB"mstr_standard"
BODY_TYPE"PLUMBING"
HDL_TAP"TRUE";
"B \NAC \NWC"6;
"S \NAC"
BN"10"102;
%"TAP"
"1","(-6250,2875)","0","mstr_standard","I218";
;
CDS_LIB"mstr_standard"
BODY_TYPE"PLUMBING"
HDL_TAP"TRUE";
"B \NAC \NWC"6;
"S \NAC"
BN"11"103;
%"TAP"
"1","(-6250,2925)","0","mstr_standard","I219";
;
CDS_LIB"mstr_standard"
BODY_TYPE"PLUMBING"
HDL_TAP"TRUE";
"B \NAC \NWC"6;
"S \NAC"
BN"12"104;
%"TAP"
"1","(-6250,2975)","0","mstr_standard","I220";
;
CDS_LIB"mstr_standard"
BODY_TYPE"PLUMBING"
HDL_TAP"TRUE";
"B \NAC \NWC"6;
"S \NAC"
BN"13"105;
%"TAP"
"1","(-6250,3075)","0","mstr_standard","I221";
;
CDS_LIB"mstr_standard"
BODY_TYPE"PLUMBING"
HDL_TAP"TRUE";
"B \NAC \NWC"6;
"S \NAC"
BN"15"107;
%"TAP"
"1","(-6250,3025)","0","mstr_standard","I222";
;
CDS_LIB"mstr_standard"
BODY_TYPE"PLUMBING"
HDL_TAP"TRUE";
"B \NAC \NWC"6;
"S \NAC"
BN"14"106;
%"TAP"
"1","(-6250,3225)","0","mstr_standard","I223";
;
CDS_LIB"mstr_standard"
BODY_TYPE"PLUMBING"
HDL_TAP"TRUE";
"B \NAC \NWC"6;
"S \NAC"
BN"18"110;
%"TAP"
"1","(-6250,3175)","0","mstr_standard","I224";
;
CDS_LIB"mstr_standard"
BODY_TYPE"PLUMBING"
HDL_TAP"TRUE";
"B \NAC \NWC"6;
"S \NAC"
BN"17"109;
%"TAP"
"1","(-6250,3125)","0","mstr_standard","I225";
;
CDS_LIB"mstr_standard"
BODY_TYPE"PLUMBING"
HDL_TAP"TRUE";
"B \NAC \NWC"6;
"S \NAC"
BN"16"108;
%"TAP"
"1","(-6250,3375)","0","mstr_standard","I226";
;
CDS_LIB"mstr_standard"
BODY_TYPE"PLUMBING"
HDL_TAP"TRUE";
"B \NAC \NWC"6;
"S \NAC"
BN"21"113;
%"TAP"
"1","(-6250,3425)","0","mstr_standard","I227";
;
CDS_LIB"mstr_standard"
BODY_TYPE"PLUMBING"
HDL_TAP"TRUE";
"B \NAC \NWC"6;
"S \NAC"
BN"22"114;
%"TAP"
"1","(-6250,3325)","0","mstr_standard","I228";
;
CDS_LIB"mstr_standard"
BODY_TYPE"PLUMBING"
HDL_TAP"TRUE";
"B \NAC \NWC"6;
"S \NAC"
BN"20"112;
%"TAP"
"1","(-6250,3475)","0","mstr_standard","I229";
;
CDS_LIB"mstr_standard"
BODY_TYPE"PLUMBING"
HDL_TAP"TRUE";
"B \NAC \NWC"6;
"S \NAC"
BN"23"115;
%"TAP"
"1","(-6250,3275)","0","mstr_standard","I230";
;
CDS_LIB"mstr_standard"
BODY_TYPE"PLUMBING"
HDL_TAP"TRUE";
"B \NAC \NWC"6;
"S \NAC"
BN"19"111;
%"TAP"
"1","(-6250,3625)","0","mstr_standard","I231";
;
CDS_LIB"mstr_standard"
BODY_TYPE"PLUMBING"
HDL_TAP"TRUE";
"B \NAC \NWC"6;
"S \NAC"
BN"26"117;
%"TAP"
"1","(-6250,3675)","0","mstr_standard","I232";
;
CDS_LIB"mstr_standard"
BODY_TYPE"PLUMBING"
HDL_TAP"TRUE";
"B \NAC \NWC"6;
"S \NAC"
BN"27"118;
%"TAP"
"1","(-6250,3575)","0","mstr_standard","I233";
;
CDS_LIB"mstr_standard"
BODY_TYPE"PLUMBING"
HDL_TAP"TRUE";
"B \NAC \NWC"6;
"S \NAC"
BN"25"116;
%"TAP"
"1","(-6250,3725)","0","mstr_standard","I234";
;
CDS_LIB"mstr_standard"
BODY_TYPE"PLUMBING"
HDL_TAP"TRUE";
"B \NAC \NWC"6;
"S \NAC"
BN"28"119;
%"TAP"
"1","(-6250,3525)","0","mstr_standard","I235";
;
CDS_LIB"mstr_standard"
BODY_TYPE"PLUMBING"
HDL_TAP"TRUE";
"B \NAC \NWC"6;
"S \NAC"
BN"24"37;
%"TAP"
"1","(-6250,3975)","0","mstr_standard","I236";
;
CDS_LIB"mstr_standard"
BODY_TYPE"PLUMBING"
HDL_TAP"TRUE";
"B \NAC \NWC"5;
"S \NAC"
BN"0"122;
%"TAP"
"1","(-6250,3825)","0","mstr_standard","I237";
;
CDS_LIB"mstr_standard"
BODY_TYPE"PLUMBING"
HDL_TAP"TRUE";
"B \NAC \NWC"6;
"S \NAC"
BN"30"38;
%"TAP"
"1","(-6250,3875)","0","mstr_standard","I238";
;
CDS_LIB"mstr_standard"
BODY_TYPE"PLUMBING"
HDL_TAP"TRUE";
"B \NAC \NWC"6;
"S \NAC"
BN"31"121;
%"TAP"
"1","(-6250,3775)","0","mstr_standard","I239";
;
CDS_LIB"mstr_standard"
BODY_TYPE"PLUMBING"
HDL_TAP"TRUE";
"B \NAC \NWC"6;
"S \NAC"
BN"29"120;
%"TAP"
"1","(-6250,4075)","0","mstr_standard","I240";
;
CDS_LIB"mstr_standard"
BODY_TYPE"PLUMBING"
HDL_TAP"TRUE";
"B \NAC \NWC"5;
"S \NAC"
BN"2"124;
%"TAP"
"1","(-6250,4025)","0","mstr_standard","I241";
;
CDS_LIB"mstr_standard"
BODY_TYPE"PLUMBING"
HDL_TAP"TRUE";
"B \NAC \NWC"5;
"S \NAC"
BN"1"123;
%"TAP"
"1","(-6250,4125)","0","mstr_standard","I242";
;
CDS_LIB"mstr_standard"
BODY_TYPE"PLUMBING"
HDL_TAP"TRUE";
"B \NAC \NWC"5;
"S \NAC"
BN"3"125;
%"TAP"
"1","(-6250,4175)","0","mstr_standard","I243";
;
CDS_LIB"mstr_standard"
BODY_TYPE"PLUMBING"
HDL_TAP"TRUE";
"B \NAC \NWC"5;
"S \NAC"
BN"4"126;
%"TAP"
"1","(-6250,4225)","0","mstr_standard","I244";
;
CDS_LIB"mstr_standard"
BODY_TYPE"PLUMBING"
HDL_TAP"TRUE";
"B \NAC \NWC"5;
"S \NAC"
BN"5"127;
%"TAP"
"1","(-6250,4325)","0","mstr_standard","I245";
;
CDS_LIB"mstr_standard"
BODY_TYPE"PLUMBING"
HDL_TAP"TRUE";
"B \NAC \NWC"5;
"S \NAC"
BN"7"129;
%"TAP"
"1","(-6250,4275)","0","mstr_standard","I246";
;
CDS_LIB"mstr_standard"
BODY_TYPE"PLUMBING"
HDL_TAP"TRUE";
"B \NAC \NWC"5;
"S \NAC"
BN"6"128;
%"TAP"
"1","(-6250,4375)","0","mstr_standard","I247";
;
CDS_LIB"mstr_standard"
BODY_TYPE"PLUMBING"
HDL_TAP"TRUE";
"B \NAC \NWC"5;
"S \NAC"
BN"8"130;
%"TAP"
"1","(-6250,4425)","0","mstr_standard","I248";
;
CDS_LIB"mstr_standard"
BODY_TYPE"PLUMBING"
HDL_TAP"TRUE";
"B \NAC \NWC"5;
"S \NAC"
BN"9"131;
%"TAP"
"1","(-6250,4475)","0","mstr_standard","I249";
;
CDS_LIB"mstr_standard"
BODY_TYPE"PLUMBING"
HDL_TAP"TRUE";
"B \NAC \NWC"5;
"S \NAC"
BN"10"132;
%"TAP"
"1","(-6250,4675)","0","mstr_standard","I250";
;
CDS_LIB"mstr_standard"
BODY_TYPE"PLUMBING"
HDL_TAP"TRUE";
"B \NAC \NWC"5;
"S \NAC"
BN"14"136;
%"TAP"
"1","(-6250,4725)","0","mstr_standard","I251";
;
CDS_LIB"mstr_standard"
BODY_TYPE"PLUMBING"
HDL_TAP"TRUE";
"B \NAC \NWC"5;
"S \NAC"
BN"15"137;
%"TAP"
"1","(-6250,4625)","0","mstr_standard","I252";
;
CDS_LIB"mstr_standard"
BODY_TYPE"PLUMBING"
HDL_TAP"TRUE";
"B \NAC \NWC"5;
"S \NAC"
BN"13"135;
%"TAP"
"1","(-6250,4575)","0","mstr_standard","I253";
;
CDS_LIB"mstr_standard"
BODY_TYPE"PLUMBING"
HDL_TAP"TRUE";
"B \NAC \NWC"5;
"S \NAC"
BN"12"134;
%"TAP"
"1","(-6250,4525)","0","mstr_standard","I254";
;
CDS_LIB"mstr_standard"
BODY_TYPE"PLUMBING"
HDL_TAP"TRUE";
"B \NAC \NWC"5;
"S \NAC"
BN"11"133;
%"TAP"
"1","(-6250,4825)","0","mstr_standard","I255";
;
CDS_LIB"mstr_standard"
BODY_TYPE"PLUMBING"
HDL_TAP"TRUE";
"B \NAC \NWC"5;
"S \NAC"
BN"17"139;
%"TAP"
"1","(-6250,4875)","0","mstr_standard","I256";
;
CDS_LIB"mstr_standard"
BODY_TYPE"PLUMBING"
HDL_TAP"TRUE";
"B \NAC \NWC"5;
"S \NAC"
BN"18"89;
%"TAP"
"1","(-6250,4775)","0","mstr_standard","I257";
;
CDS_LIB"mstr_standard"
BODY_TYPE"PLUMBING"
HDL_TAP"TRUE";
"B \NAC \NWC"5;
"S \NAC"
BN"16"138;
%"TAP"
"1","(-6250,4975)","0","mstr_standard","I258";
;
CDS_LIB"mstr_standard"
BODY_TYPE"PLUMBING"
HDL_TAP"TRUE";
"B \NAC \NWC"5;
"S \NAC"
BN"20"140;
%"TAP"
"1","(-6250,4925)","0","mstr_standard","I259";
;
CDS_LIB"mstr_standard"
BODY_TYPE"PLUMBING"
HDL_TAP"TRUE";
"B \NAC \NWC"5;
"S \NAC"
BN"19"88;
%"TAP"
"1","(-7950,5125)","2","mstr_standard","I263";
;
CDS_LIB"mstr_standard"
BODY_TYPE"PLUMBING"
HDL_TAP"TRUE";
"B \NAC \NWC"3;
"S \NAC"
BN"6"159;
%"TAP"
"1","(-7950,5025)","2","mstr_standard","I264";
;
CDS_LIB"mstr_standard"
BODY_TYPE"PLUMBING"
HDL_TAP"TRUE";
"B \NAC \NWC"3;
"S \NAC"
BN"4"162;
%"TAP"
"1","(-7950,5075)","2","mstr_standard","I265";
;
CDS_LIB"mstr_standard"
BODY_TYPE"PLUMBING"
HDL_TAP"TRUE";
"B \NAC \NWC"3;
"S \NAC"
BN"5"160;
%"TAP"
"1","(-7950,5225)","2","mstr_standard","I266";
;
CDS_LIB"mstr_standard"
BODY_TYPE"PLUMBING"
HDL_TAP"TRUE";
"B \NAC \NWC"2;
"S \NAC"
BN"0"171;
%"TAP"
"1","(-7950,5275)","2","mstr_standard","I267";
;
CDS_LIB"mstr_standard"
BODY_TYPE"PLUMBING"
HDL_TAP"TRUE";
"B \NAC \NWC"2;
"S \NAC"
BN"1"169;
%"TAP"
"1","(-7950,5325)","2","mstr_standard","I268";
;
CDS_LIB"mstr_standard"
BODY_TYPE"PLUMBING"
HDL_TAP"TRUE";
"B \NAC \NWC"2;
"S \NAC"
BN"2"167;
%"TAP"
"1","(-7950,5375)","2","mstr_standard","I269";
;
CDS_LIB"mstr_standard"
BODY_TYPE"PLUMBING"
HDL_TAP"TRUE";
"B \NAC \NWC"2;
"S \NAC"
BN"3"165;
%"TAP"
"1","(-7950,5475)","2","mstr_standard","I270";
;
CDS_LIB"mstr_standard"
BODY_TYPE"PLUMBING"
HDL_TAP"TRUE";
"B \NAC \NWC"2;
"S \NAC"
BN"5"161;
%"TAP"
"1","(-7950,5425)","2","mstr_standard","I271";
;
CDS_LIB"mstr_standard"
BODY_TYPE"PLUMBING"
HDL_TAP"TRUE";
"B \NAC \NWC"2;
"S \NAC"
BN"4"163;
%"TAP"
"1","(-7950,5525)","2","mstr_standard","I272";
;
CDS_LIB"mstr_standard"
BODY_TYPE"PLUMBING"
HDL_TAP"TRUE";
"B \NAC \NWC"2;
"S \NAC"
BN"6"87;
%"TAP"
"1","(-6250,5125)","0","mstr_standard","I273";
;
CDS_LIB"mstr_standard"
BODY_TYPE"PLUMBING"
HDL_TAP"TRUE";
"B \NAC \NWC"5;
"S \NAC"
BN"23"143;
%"TAP"
"1","(-6250,5025)","0","mstr_standard","I274";
;
CDS_LIB"mstr_standard"
BODY_TYPE"PLUMBING"
HDL_TAP"TRUE";
"B \NAC \NWC"5;
"S \NAC"
BN"21"141;
%"TAP"
"1","(-6250,5075)","0","mstr_standard","I275";
;
CDS_LIB"mstr_standard"
BODY_TYPE"PLUMBING"
HDL_TAP"TRUE";
"B \NAC \NWC"5;
"S \NAC"
BN"22"142;
%"TAP"
"1","(-6250,5175)","0","mstr_standard","I276";
;
CDS_LIB"mstr_standard"
BODY_TYPE"PLUMBING"
HDL_TAP"TRUE";
"B \NAC \NWC"5;
"S \NAC"
BN"24"144;
%"TAP"
"1","(-6250,5225)","0","mstr_standard","I277";
;
CDS_LIB"mstr_standard"
BODY_TYPE"PLUMBING"
HDL_TAP"TRUE";
"B \NAC \NWC"5;
"S \NAC"
BN"25"44;
%"TAP"
"1","(-6250,5275)","0","mstr_standard","I278";
;
CDS_LIB"mstr_standard"
BODY_TYPE"PLUMBING"
HDL_TAP"TRUE";
"B \NAC \NWC"5;
"S \NAC"
BN"26"43;
%"TAP"
"1","(-6250,5525)","0","mstr_standard","I279";
;
CDS_LIB"mstr_standard"
BODY_TYPE"PLUMBING"
HDL_TAP"TRUE";
"B \NAC \NWC"5;
"S \NAC"
BN"31"176;
%"TAP"
"1","(-6250,5325)","0","mstr_standard","I280";
;
CDS_LIB"mstr_standard"
BODY_TYPE"PLUMBING"
HDL_TAP"TRUE";
"B \NAC \NWC"5;
"S \NAC"
BN"27"85;
%"TAP"
"1","(-6250,5375)","0","mstr_standard","I281";
;
CDS_LIB"mstr_standard"
BODY_TYPE"PLUMBING"
HDL_TAP"TRUE";
"B \NAC \NWC"5;
"S \NAC"
BN"28"86;
%"TAP"
"1","(-6250,5475)","0","mstr_standard","I282";
;
CDS_LIB"mstr_standard"
BODY_TYPE"PLUMBING"
HDL_TAP"TRUE";
"B \NAC \NWC"5;
"S \NAC"
BN"30"146;
%"TAP"
"1","(-6250,5425)","0","mstr_standard","I283";
;
CDS_LIB"mstr_standard"
BODY_TYPE"PLUMBING"
HDL_TAP"TRUE";
"B \NAC \NWC"5;
"S \NAC"
BN"29"145;
%"TAP"
"1","(-3650,2700)","0","mstr_standard","I285";
;
CDS_LIB"mstr_standard"
BODY_TYPE"PLUMBING"
HDL_TAP"TRUE";
"B \NAC \NWC"8;
"S \NAC"
BN"0"78;
%"TAP"
"1","(-3650,2800)","0","mstr_standard","I286";
;
CDS_LIB"mstr_standard"
BODY_TYPE"PLUMBING"
HDL_TAP"TRUE";
"B \NAC \NWC"8;
"S \NAC"
BN"1"74;
%"TAP"
"1","(-3450,2850)","0","mstr_standard","I287";
;
CDS_LIB"mstr_standard"
BODY_TYPE"PLUMBING"
HDL_TAP"TRUE";
"B \NAC \NWC"7;
"S \NAC"
BN"2"71;
%"TAP"
"1","(-3450,2750)","0","mstr_standard","I288";
;
CDS_LIB"mstr_standard"
BODY_TYPE"PLUMBING"
HDL_TAP"TRUE";
"B \NAC \NWC"7;
"S \NAC"
BN"1"75;
%"TAP"
"1","(-3450,2650)","0","mstr_standard","I289";
;
CDS_LIB"mstr_standard"
BODY_TYPE"PLUMBING"
HDL_TAP"TRUE";
"B \NAC \NWC"7;
"S \NAC"
BN"0"79;
%"TAP"
"1","(-3650,2900)","0","mstr_standard","I290";
;
CDS_LIB"mstr_standard"
BODY_TYPE"PLUMBING"
HDL_TAP"TRUE";
"B \NAC \NWC"8;
"S \NAC"
BN"2"70;
%"TAP"
"1","(-3650,3000)","0","mstr_standard","I291";
;
CDS_LIB"mstr_standard"
BODY_TYPE"PLUMBING"
HDL_TAP"TRUE";
"B \NAC \NWC"8;
"S \NAC"
BN"3"66;
%"TAP"
"1","(-3650,3100)","0","mstr_standard","I292";
;
CDS_LIB"mstr_standard"
BODY_TYPE"PLUMBING"
HDL_TAP"TRUE";
"B \NAC \NWC"8;
"S \NAC"
BN"4"62;
%"TAP"
"1","(-3450,2950)","0","mstr_standard","I293";
;
CDS_LIB"mstr_standard"
BODY_TYPE"PLUMBING"
HDL_TAP"TRUE";
"B \NAC \NWC"7;
"S \NAC"
BN"3"67;
%"TAP"
"1","(-3450,3050)","0","mstr_standard","I294";
;
CDS_LIB"mstr_standard"
BODY_TYPE"PLUMBING"
HDL_TAP"TRUE";
"B \NAC \NWC"7;
"S \NAC"
BN"4"63;
%"TAP"
"1","(-3650,3200)","0","mstr_standard","I295";
;
CDS_LIB"mstr_standard"
BODY_TYPE"PLUMBING"
HDL_TAP"TRUE";
"B \NAC \NWC"8;
"S \NAC"
BN"5"58;
%"TAP"
"1","(-3650,3300)","0","mstr_standard","I296";
;
CDS_LIB"mstr_standard"
BODY_TYPE"PLUMBING"
HDL_TAP"TRUE";
"B \NAC \NWC"8;
"S \NAC"
BN"6"55;
%"TAP"
"1","(-3450,3350)","0","mstr_standard","I297";
;
CDS_LIB"mstr_standard"
BODY_TYPE"PLUMBING"
HDL_TAP"TRUE";
"B \NAC \NWC"7;
"S \NAC"
BN"7"53;
%"TAP"
"1","(-3450,3250)","0","mstr_standard","I298";
;
CDS_LIB"mstr_standard"
BODY_TYPE"PLUMBING"
HDL_TAP"TRUE";
"B \NAC \NWC"7;
"S \NAC"
BN"6"56;
%"TAP"
"1","(-3450,3150)","0","mstr_standard","I299";
;
CDS_LIB"mstr_standard"
BODY_TYPE"PLUMBING"
HDL_TAP"TRUE";
"B \NAC \NWC"7;
"S \NAC"
BN"5"59;
%"TAP"
"1","(-3650,3400)","0","mstr_standard","I300";
;
CDS_LIB"mstr_standard"
BODY_TYPE"PLUMBING"
HDL_TAP"TRUE";
"B \NAC \NWC"8;
"S \NAC"
BN"7"80;
%"TAP"
"1","(-3650,3500)","0","mstr_standard","I301";
;
CDS_LIB"mstr_standard"
BODY_TYPE"PLUMBING"
HDL_TAP"TRUE";
"B \NAC \NWC"8;
"S \NAC"
BN"8"82;
%"TAP"
"1","(-3650,3600)","0","mstr_standard","I302";
;
CDS_LIB"mstr_standard"
BODY_TYPE"PLUMBING"
HDL_TAP"TRUE";
"B \NAC \NWC"8;
"S \NAC"
BN"9"45;
%"TAP"
"1","(-3450,3450)","0","mstr_standard","I303";
;
CDS_LIB"mstr_standard"
BODY_TYPE"PLUMBING"
HDL_TAP"TRUE";
"B \NAC \NWC"7;
"S \NAC"
BN"8"81;
%"TAP"
"1","(-3450,3550)","0","mstr_standard","I304";
;
CDS_LIB"mstr_standard"
BODY_TYPE"PLUMBING"
HDL_TAP"TRUE";
"B \NAC \NWC"7;
"S \NAC"
BN"9"46;
%"TAP"
"1","(-3650,3750)","0","mstr_standard","I305";
;
CDS_LIB"mstr_standard"
BODY_TYPE"PLUMBING"
HDL_TAP"TRUE";
"B \NAC \NWC"10;
"S \NAC"
BN"0"48;
%"TAP"
"1","(-3650,3850)","0","mstr_standard","I306";
;
CDS_LIB"mstr_standard"
BODY_TYPE"PLUMBING"
HDL_TAP"TRUE";
"B \NAC \NWC"10;
"S \NAC"
BN"1"76;
%"TAP"
"1","(-3450,3700)","0","mstr_standard","I307";
;
CDS_LIB"mstr_standard"
BODY_TYPE"PLUMBING"
HDL_TAP"TRUE";
"B \NAC \NWC"9;
"S \NAC"
BN"0"47;
%"TAP"
"1","(-3450,3800)","0","mstr_standard","I308";
;
CDS_LIB"mstr_standard"
BODY_TYPE"PLUMBING"
HDL_TAP"TRUE";
"B \NAC \NWC"9;
"S \NAC"
BN"1"77;
%"TAP"
"1","(-3650,3950)","0","mstr_standard","I309";
;
CDS_LIB"mstr_standard"
BODY_TYPE"PLUMBING"
HDL_TAP"TRUE";
"B \NAC \NWC"10;
"S \NAC"
BN"2"72;
%"TAP"
"1","(-3650,4050)","0","mstr_standard","I310";
;
CDS_LIB"mstr_standard"
BODY_TYPE"PLUMBING"
HDL_TAP"TRUE";
"B \NAC \NWC"10;
"S \NAC"
BN"3"68;
%"TAP"
"1","(-3450,3900)","0","mstr_standard","I311";
;
CDS_LIB"mstr_standard"
BODY_TYPE"PLUMBING"
HDL_TAP"TRUE";
"B \NAC \NWC"9;
"S \NAC"
BN"2"73;
%"TAP"
"1","(-3450,4000)","0","mstr_standard","I312";
;
CDS_LIB"mstr_standard"
BODY_TYPE"PLUMBING"
HDL_TAP"TRUE";
"B \NAC \NWC"9;
"S \NAC"
BN"3"69;
%"TAP"
"1","(-3450,4100)","0","mstr_standard","I313";
;
CDS_LIB"mstr_standard"
BODY_TYPE"PLUMBING"
HDL_TAP"TRUE";
"B \NAC \NWC"9;
"S \NAC"
BN"4"65;
%"TAP"
"1","(-3650,4150)","0","mstr_standard","I316";
;
CDS_LIB"mstr_standard"
BODY_TYPE"PLUMBING"
HDL_TAP"TRUE";
"B \NAC \NWC"10;
"S \NAC"
BN"4"64;
%"TAP"
"1","(-3650,4250)","0","mstr_standard","I317";
;
CDS_LIB"mstr_standard"
BODY_TYPE"PLUMBING"
HDL_TAP"TRUE";
"B \NAC \NWC"10;
"S \NAC"
BN"5"60;
%"TAP"
"1","(-3650,4350)","0","mstr_standard","I318";
;
CDS_LIB"mstr_standard"
BODY_TYPE"PLUMBING"
HDL_TAP"TRUE";
"B \NAC \NWC"10;
"S \NAC"
BN"6"83;
%"TAP"
"1","(-3450,4400)","0","mstr_standard","I319";
;
CDS_LIB"mstr_standard"
BODY_TYPE"PLUMBING"
HDL_TAP"TRUE";
"B \NAC \NWC"9;
"S \NAC"
BN"7"84;
%"TAP"
"1","(-3450,4300)","0","mstr_standard","I320";
;
CDS_LIB"mstr_standard"
BODY_TYPE"PLUMBING"
HDL_TAP"TRUE";
"B \NAC \NWC"9;
"S \NAC"
BN"6"57;
%"TAP"
"1","(-3450,4200)","0","mstr_standard","I321";
;
CDS_LIB"mstr_standard"
BODY_TYPE"PLUMBING"
HDL_TAP"TRUE";
"B \NAC \NWC"9;
"S \NAC"
BN"5"61;
%"TAP"
"1","(-3650,4450)","0","mstr_standard","I322";
;
CDS_LIB"mstr_standard"
BODY_TYPE"PLUMBING"
HDL_TAP"TRUE";
"B \NAC \NWC"10;
"S \NAC"
BN"7"54;
%"TAP"
"1","(-3650,4550)","0","mstr_standard","I323";
;
CDS_LIB"mstr_standard"
BODY_TYPE"PLUMBING"
HDL_TAP"TRUE";
"B \NAC \NWC"10;
"S \NAC"
BN"8"51;
%"TAP"
"1","(-3650,4650)","0","mstr_standard","I324";
;
CDS_LIB"mstr_standard"
BODY_TYPE"PLUMBING"
HDL_TAP"TRUE";
"B \NAC \NWC"10;
"S \NAC"
BN"9"49;
%"TAP"
"1","(-3450,4600)","0","mstr_standard","I325";
;
CDS_LIB"mstr_standard"
BODY_TYPE"PLUMBING"
HDL_TAP"TRUE";
"B \NAC \NWC"9;
"S \NAC"
BN"9"50;
%"TAP"
"1","(-3450,4500)","0","mstr_standard","I326";
;
CDS_LIB"mstr_standard"
BODY_TYPE"PLUMBING"
HDL_TAP"TRUE";
"B \NAC \NWC"9;
"S \NAC"
BN"8"52;
%"GND"
"1","(-6650,1175)","0","mstr_symbols","I332";
;
BOM_COST"MEM"
CDS_LIB"mstr_symbols"
SIZE"1B"
BODY_TYPE"PLUMBING"
VOLTAGE"0.0"
HDL_POWER"GND";
"A\NAC"11;
%"Q_RES"
"2","(-6650,1400)","0","pure_quanta","I349";
;
LOCATION"R761"
$SEC"1"
CDS_SEC"1"
WATTAGE"1/16W"
MATERIAL"CHIP"
TOLERANCE"1%"
VALUE"15.4K"
PART_NUMBER"CS31542FB02"
PACK_TYPE"0402LF"
CDS_LIB"pure_quanta";
"A"
$PN"1"178;
"B"
$PN"2"11;
%"SCONN288_DDR506112002KQ"
"1","(-7100,3775)","0","pure_quanta","I350";
;
LOCATION"J15"
$SEC"1"
CDS_SEC"1"
PART_TYPE"SMLF"
VALUE"SCONN288_DDR506112002KQ"
MATERIAL"IO"
PART_NUMBER"DFHST8FS479"
CDS_LMAN_SYM_OUTLINE"-450,1900,450,-1850"
NEEDS_NO_SIZE"TRUE"
CDS_LIB"pure_quanta";
"PWR_GOOD||FAIL_N"
$PN"147"16;
"DQ31_A"
$PN"194"176;
"CB7_A"
$PN"205"175;
"CB4_A"
$PN"58"174;
"CB1_A"
$PN"53"173;
"CB7_B"
$PN"236"172;
"ALERT_N \B"
$PN"62"19;
"CA0_A"
$PN"66"171;
"CA0_B"
$PN"76"170;
"CA1_A"
$PN"211"169;
"CA1_B"
$PN"221"168;
"CA2_A"
$PN"68"167;
"CA2_B"
$PN"78"166;
"CA3_A"
$PN"213"165;
"CA3_B"
$PN"223"164;
"CA4_A"
$PN"70"163;
"CA4_B"
$PN"80"162;
"CA5_A"
$PN"215"161;
"CA5_B"
$PN"225"160;
"CA6_A"
$PN"72"87;
"CA6_B"
$PN"82"159;
"CB6_A"
$PN"203"158;
"CB5_A"
$PN"60"157;
"CB3_A"
$PN"198"156;
"CB2_A"
$PN"196"155;
"CB0_A"
$PN"51"154;
"CB6_B"
$PN"234"153;
"CB5_B"
$PN"91"152;
"CB4_B"
$PN"89"151;
"CB3_B"
$PN"243"33;
"CB2_B"
$PN"241"36;
"CB1_B"
$PN"98"35;
"CB0_B"
$PN"96"34;
"CK_C \B"
$PN"218"150;
"CK_T"
$PN"217"39;
"CS0_A_N"
$PN"64"149;
"CS0_B_N"
$PN"84"40;
"CS1_A_N"
$PN"209"148;
"CS1_B_N"
$PN"229"147;
"DQ30_A"
$PN"192"146;
"DQ29_A"
$PN"49"145;
"DQ28_A"
$PN"47"86;
"DQ27_A"
$PN"187"85;
"DQ26_A"
$PN"185"43;
"DQ25_A"
$PN"42"44;
"DQ24_A"
$PN"40"144;
"DQ23_A"
$PN"183"143;
"DQ22_A"
$PN"181"142;
"DQ21_A"
$PN"38"141;
"DQ20_A"
$PN"36"140;
"DQ19_A"
$PN"176"88;
"DQ18_A"
$PN"174"89;
"DQ17_A"
$PN"31"139;
"DQ16_A"
$PN"29"138;
"DQ15_A"
$PN"172"137;
"DQ14_A"
$PN"170"136;
"DQ13_A"
$PN"27"135;
"DQ12_A"
$PN"25"134;
"DQ11_A"
$PN"165"133;
"DQ10_A"
$PN"163"132;
"DQ9_A"
$PN"20"131;
"DQ8_A"
$PN"18"130;
"DQ7_A"
$PN"161"129;
"DQ6_A"
$PN"159"128;
"DQ5_A"
$PN"16"127;
"DQ4_A"
$PN"14"126;
"DQ3_A"
$PN"154"125;
"DQ2_A"
$PN"152"124;
"DQ1_A"
$PN"9"123;
"DQ0_A"
$PN"7"122;
"DQ31_B"
$PN"287"121;
"DQ30_B"
$PN"285"38;
"DQ29_B"
$PN"142"120;
"DQ28_B"
$PN"140"119;
"DQ27_B"
$PN"280"118;
"DQ26_B"
$PN"278"117;
"DQ25_B"
$PN"135"116;
"DQ24_B"
$PN"133"37;
"DQ23_B"
$PN"276"115;
"DQ22_B"
$PN"274"114;
"DQ21_B"
$PN"131"113;
"DQ20_B"
$PN"129"112;
"DQ19_B"
$PN"269"111;
"DQ18_B"
$PN"267"110;
"DQ17_B"
$PN"124"109;
"DQ16_B"
$PN"122"108;
"DQ15_B"
$PN"265"107;
"DQ14_B"
$PN"263"106;
"DQ13_B"
$PN"120"105;
"DQ12_B"
$PN"118"104;
"DQ11_B"
$PN"258"103;
"DQ10_B"
$PN"256"102;
"DQ9_B"
$PN"113"101;
"DQ8_B"
$PN"111"100;
"DQ7_B"
$PN"254"99;
"DQ6_B"
$PN"252"98;
"DQ5_B"
$PN"109"97;
"DQ4_B"
$PN"107"96;
"DQ3_B"
$PN"247"95;
"DQ2_B"
$PN"245"94;
"DQ1_B"
$PN"102"93;
"DQ0_B"
$PN"100"92;
"HAS"
$PN"148"20;
"HSCL"
$PN"4"14;
"HSDA"
$PN"5"17;
"LBD||RSP_A_N"
$PN"86"91;
"LBS||RSP_B_N"
$PN"87"90;
"PAR_A"
$PN"74"41;
"PAR_B"
$PN"227"42;
"RESET_N \B"
$PN"207"32;
"RFU6"
$PN"232"21;
"RFU5"
$PN"231"22;
"RFU4"
$PN"220"23;
"RFU3"
$PN"150"28;
"RFU2"
$PN"149"31;
"RFU1"
$PN"144"30;
"RFU0"
$PN"2"29;
"VIN_MGMT"
$PN"3"18;
%"SCONN288_DDR506112002KQ"
"3","(-1225,3575)","0","pure_quanta","I352";
;
LOCATION"J15"
$SEC"3"
CDS_SEC"3"
VALUE"SCONN288_DDR506112002KQ"
MATERIAL"IO"
PART_TYPE"SMLF"
PART_NUMBER"DFHST8FS479"
CDS_LMAN_SYM_OUTLINE"-450,1800,450,-1750"
NEEDS_NO_SIZE"TRUE"
CDS_LIB"pure_quanta";
"G3"
$PN"G3"26;
"G2"
$PN"G2"26;
"G1"
$PN"G1"26;
"VSS62"
$PN"141"26;
"VSS61"
$PN"139"26;
"VSS60"
$PN"136"26;
"VSS58"
$PN"132"26;
"VSS104"
$PN"240"27;
"VSS102"
$PN"235"27;
"VSS100"
$PN"230"27;
"VIN_BULK2"
$PN"146"24;
"VIN_BULK1"
$PN"145"24;
"VIN_BULK0"
$PN"1"24;
"VSS126"
$PN"288"27;
"VSS125"
$PN"286"27;
"VSS124"
$PN"284"27;
"VSS123"
$PN"281"27;
"VSS122"
$PN"279"27;
"VSS121"
$PN"277"27;
"VSS120"
$PN"275"27;
"VSS119"
$PN"273"27;
"VSS118"
$PN"270"27;
"VSS117"
$PN"268"27;
"VSS116"
$PN"266"27;
"VSS115"
$PN"264"27;
"VSS114"
$PN"262"27;
"VSS113"
$PN"259"27;
"VSS112"
$PN"257"27;
"VSS111"
$PN"255"27;
"VSS110"
$PN"253"27;
"VSS109"
$PN"251"27;
"VSS108"
$PN"248"27;
"VSS107"
$PN"246"27;
"VSS106"
$PN"244"27;
"VSS105"
$PN"242"27;
"VSS103"
$PN"237"27;
"VSS101"
$PN"233"27;
"VSS99"
$PN"228"27;
"VSS98"
$PN"226"27;
"VSS97"
$PN"224"27;
"VSS96"
$PN"222"27;
"VSS95"
$PN"219"27;
"VSS94"
$PN"216"27;
"VSS93"
$PN"214"27;
"VSS92"
$PN"212"27;
"VSS91"
$PN"210"27;
"VSS90"
$PN"208"27;
"VSS89"
$PN"206"27;
"VSS88"
$PN"204"27;
"VSS87"
$PN"202"27;
"VSS86"
$PN"199"27;
"VSS85"
$PN"197"27;
"VSS84"
$PN"195"27;
"VSS83"
$PN"193"27;
"VSS82"
$PN"191"27;
"VSS81"
$PN"188"27;
"VSS80"
$PN"186"27;
"VSS79"
$PN"184"27;
"VSS78"
$PN"182"27;
"VSS77"
$PN"180"27;
"VSS76"
$PN"177"27;
"VSS75"
$PN"175"27;
"VSS74"
$PN"173"27;
"VSS73"
$PN"171"27;
"VSS72"
$PN"169"27;
"VSS71"
$PN"166"27;
"VSS70"
$PN"164"27;
"VSS69"
$PN"162"27;
"VSS68"
$PN"160"27;
"VSS67"
$PN"158"27;
"VSS66"
$PN"155"27;
"VSS65"
$PN"153"27;
"VSS64"
$PN"151"27;
"VSS63"
$PN"143"26;
"VSS59"
$PN"134"26;
"VSS57"
$PN"130"26;
"VSS56"
$PN"128"26;
"VSS55"
$PN"125"26;
"VSS54"
$PN"123"26;
"VSS53"
$PN"121"26;
"VSS52"
$PN"119"26;
"VSS51"
$PN"117"26;
"VSS50"
$PN"114"26;
"VSS49"
$PN"112"26;
"VSS48"
$PN"110"26;
"VSS47"
$PN"108"26;
"VSS46"
$PN"106"26;
"VSS45"
$PN"103"26;
"VSS44"
$PN"101"26;
"VSS43"
$PN"99"26;
"VSS42"
$PN"97"26;
"VSS41"
$PN"95"26;
"VSS40"
$PN"92"26;
"VSS39"
$PN"90"26;
"VSS38"
$PN"88"26;
"VSS37"
$PN"85"26;
"VSS36"
$PN"83"26;
"VSS35"
$PN"81"26;
"VSS34"
$PN"79"26;
"VSS33"
$PN"77"26;
"VSS32"
$PN"75"26;
"VSS31"
$PN"73"26;
"VSS30"
$PN"71"26;
"VSS29"
$PN"69"26;
"VSS28"
$PN"67"26;
"VSS27"
$PN"65"26;
"VSS26"
$PN"63"26;
"VSS25"
$PN"61"26;
"VSS24"
$PN"59"26;
"VSS23"
$PN"57"26;
"VSS22"
$PN"54"26;
"VSS21"
$PN"52"26;
"VSS20"
$PN"50"26;
"VSS19"
$PN"48"26;
"VSS18"
$PN"46"26;
"VSS17"
$PN"43"26;
"VSS16"
$PN"41"26;
"VSS15"
$PN"39"26;
"VSS14"
$PN"37"26;
"VSS13"
$PN"35"26;
"VSS12"
$PN"32"26;
"VSS11"
$PN"30"26;
"VSS10"
$PN"28"26;
"VSS9"
$PN"26"26;
"VSS8"
$PN"24"26;
"VSS7"
$PN"21"26;
"VSS6"
$PN"19"26;
"VSS5"
$PN"17"26;
"VSS4"
$PN"15"26;
"VSS3"
$PN"13"26;
"VSS2"
$PN"10"26;
"VSS1"
$PN"8"26;
"VSS0"
$PN"6"26;
%"GND"
"1","(-9050,3100)","0","mstr_symbols","I361";
;
BOM_COST"MEM"
SIZE"1B"
CDS_LIB"mstr_symbols"
BODY_TYPE"PLUMBING"
VOLTAGE"0"
ROOM"MEM_EFGH_DECOUPLING_CAPS"
HDL_POWER"GND";
"A\NAC"12;
%"Q_CAP"
"1","(-9050,3325)","2","pure_quanta","I362";
;
LOCATION"C92"
$SEC"1"
CDS_SEC"1"
TOLERANCE"10%"
VOLTAGE"25V"
MATERIAL"X7R"
VALUE"0.1UF"
PACK_TYPE"0402"
PART_NUMBER"CH4104K1B00"
BOM_COST"MEM"
CDS_LIB"pure_quanta"
ROOM"MEM_CH_A_CPU0_DIMM1";
"B"
$PN"2"12;
"A"
$PN"1"18;
%"Q_RES"
"1","(-8675,2275)","2","pure_quanta","I364";
;
LOCATION"R292"
$SEC"1"
CDS_SEC"1"
VALUE"0"
BOM_COST"MEM"
CDS_LIB"pure_quanta"
WATTAGE"1/16W"
MATERIAL"CHIP"
TOLERANCE"5%"
PART_NUMBER"CS00002JB38"
PACK_TYPE"0402LF"
ROOM"RST_CPU0_PLD_TO_DIMM";
"B"
$PN"2"177;
"A"
$PN"1"16;
%"Q_RES"
"2","(-8550,2425)","0","pure_quanta","I365";
;
LOCATION"R90"
$SEC"1"
CDS_SEC"1"
PACK_TYPE"0402LF"
VALUE"1K"
TOLERANCE"5%"
MATERIAL"EMPTY"
WATTAGE"1/16W"
CDS_LIB"pure_quanta"
BOM_COST"MEM"
PART_NUMBER"TMP_QCS21002JB34"
ROOM"MEM_CH_A_CPU0_DIMM1";
"A"
$PN"1"13;
"B"
$PN"2"16;
%"VCC_CORE"
"1","(-8550,2600)","0","mstr_symbols","I366";
;
HDL_POWER"P3V3_STBY"
CDS_LIB"mstr_symbols"
VOLTAGE"3.3"
ROOM"PVCCINFAON_CPU0_CTRL";
"A"13;
%"SCONN288_DDR506112002KQ"
"2","(-4600,3650)","0","pure_quanta","I367";
;
LOCATION"J15"
$SEC"2"
CDS_SEC"2"
MATERIAL"IO"
PART_NUMBER"DFHST8FS479"
VALUE"SCONN288_DDR506112002KQ"
PART_TYPE"SMLF"
CDS_LMAN_SYM_OUTLINE"-600,1150,600,-1150"
NEEDS_NO_SIZE"TRUE"
CDS_LIB"pure_quanta";
"DQS7_A_C||TDQS7_A_C \B"
$PN"178"84;
"DQS6_A_T||TDQS6_A_T"
$PN"168"83;
"DQS8_B_T||TDQS8_B_T"
$PN"283"82;
"DQS8_B_C||TDQS8_B_C \B"
$PN"282"81;
"DQS7_B_T||TDQS7_B_T"
$PN"272"80;
"DQS0_A_C \B"
$PN"12"47;
"DQS0_A_T"
$PN"11"48;
"DQS0_B_C \B"
$PN"105"79;
"DQS0_B_T"
$PN"104"78;
"DQS1_A_C \B"
$PN"23"77;
"DQS1_A_T"
$PN"22"76;
"DQS1_B_C \B"
$PN"116"75;
"DQS1_B_T"
$PN"115"74;
"DQS2_A_C \B"
$PN"34"73;
"DQS2_A_T"
$PN"33"72;
"DQS2_B_C \B"
$PN"127"71;
"DQS2_B_T"
$PN"126"70;
"DQS3_A_C \B"
$PN"45"69;
"DQS3_A_T"
$PN"44"68;
"DQS3_B_C \B"
$PN"138"67;
"DQS3_B_T"
$PN"137"66;
"DQS4_A_C \B"
$PN"56"65;
"DQS4_A_T"
$PN"55"64;
"DQS4_B_C \B"
$PN"238"63;
"DQS4_B_T"
$PN"239"62;
"DQS5_A_C||TDQS5_A_C||DQS5_A_T||TDQS5_A_T \B"
$PN"156"61;
"DQS5_A_T||TDQS5_A_T"
$PN"157"60;
"DQS5_B_C||TDQS5_B_C \B"
$PN"249"59;
"DQS5_B_T||TDQS5_B_T"
$PN"250"58;
"DQS6_A_C||TDQS6_A_C||DQS6_A_T||TDQS6_A_T \B"
$PN"167"57;
"DQS6_B_C||TDQS6_B_C \B"
$PN"260"56;
"DQS6_B_T||TDQS6_B_T"
$PN"261"55;
"DQS7_A_T||TDQS7_A_T"
$PN"179"54;
"DQS7_B_C||TDQS7_B_C \B"
$PN"271"53;
"DQS8_A_C||TDQS8_A_C \B"
$PN"189"52;
"DQS8_A_T||TDQS8_A_T"
$PN"190"51;
"DQS9_A_C||TDQS9_A_C \B"
$PN"200"50;
"DQS9_A_T||TDQS9_A_T"
$PN"201"49;
"DQS9_B_C||TDQS9_B_C \B"
$PN"94"46;
"DQS9_B_T||TDQS9_B_T||DBI4_B_N"
$PN"93"45;
%"GND"
"1","(-2825,5225)","0","pure_quanta_power","I368";
;
SIZE"1B"
BOM_COST"MEM"
CDS_LIB"pure_quanta_power"
ROOM"MEM_EFGH_DECOUPLING_CAPS"
HDL_POWER"GND";
"A<SIZE-1..0>\NAC"25;
%"Q_CAP"
"1","(-2825,5575)","2","pure_quanta","I369";
;
LOCATION"C143"
$SEC"1"
CDS_SEC"1"
MATERIAL"X6S"
TOLERANCE"10%"
VALUE"10UF"
VOLTAGE"25V"
PACK_TYPE"C0805"
PART_NUMBER"CH6104KEA00"
CDS_LIB"pure_quanta"
BOM_COST"MEM"
ROOM"MEM_CH_A_CPU0_DIMM1";
"B"
$PN"2"25;
"A"
$PN"1"24;
%"Q_CAP"
"1","(-2250,5575)","2","pure_quanta","I370";
;
LOCATION"C145"
$SEC"1"
CDS_SEC"1"
MATERIAL"X6S"
TOLERANCE"10%"
VALUE"10UF"
PART_NUMBER"CH6104KEA00"
VOLTAGE"25V"
PACK_TYPE"C0805"
CDS_LIB"pure_quanta"
BOM_COST"MEM"
ROOM"MEM_CH_A_CPU0_DIMM1";
"B"
$PN"2"25;
"A"
$PN"1"24;
%"UNIVERSAL_POWER"
"1","(-2825,5900)","0","pure_quanta_power","I371";
;
HDL_POWER"P12V_MEM_1"
BOM_COST"VR_SYSTEM"
CDS_LIB"pure_quanta_power";
"A"24;
%"Q_RES"
"1","(-8000,2825)","0","pure_quanta","I372";
;
$LOCATION"R1569"
CDS_LOCATION"R1569"
$SEC"1"
CDS_SEC"1"
VALUE"49.9"
PART_NUMBER"CS04992FB07"
TOLERANCE"1%"
WATTAGE"1/16W"
PACK_TYPE"0402LF"
MATERIAL"CHIP"
CDS_LIB"pure_quanta";
"B"
$PN"2"14;
"A"
$PN"1"15;
END.
